(kicad_pcb
	(version 20260206)
	(generator "pcbnew")
	(generator_version "10.0")
	(general
		(thickness 1.6)
		(legacy_teardrops no)
	)
	(paper "A4")
	(title_block
		(title "peb — Lightning_PEB_BRD.brd")
		(comment 1 "Lightning (Wiwynn / Facebook NVMe JBOF) / footprints 1005-1012 of 2563")
	)
	(layers
		(0 "F.Cu" signal "TOP")
		(4 "In1.Cu" signal "L2GND")
		(6 "In2.Cu" signal "L3")
		(8 "In3.Cu" signal "L4VCC")
		(10 "In4.Cu" signal "L5VCC")
		(12 "In5.Cu" signal "L6")
		(14 "In6.Cu" signal "L7GND")
		(2 "B.Cu" signal "BOTTOM")
		(9 "F.Adhes" user "F.Adhesive")
		(11 "B.Adhes" user "B.Adhesive")
		(13 "F.Paste" user "Package Geometry/Pastemask Top")
		(15 "B.Paste" user "Package Geometry/Pastemask Bottom")
		(5 "F.SilkS" user "Ref Des/Silkscreen Top")
		(7 "B.SilkS" user "Ref Des/Silkscreen Bottom")
		(1 "F.Mask" user "Board Geometry/Soldermask Top")
		(3 "B.Mask" user "Board Geometry/Soldermask Bottom")
		(17 "Dwgs.User" user "User.Drawings")
		(19 "Cmts.User" user "User.Comments")
		(21 "Eco1.User" user "User.Eco1")
		(23 "Eco2.User" user "User.Eco2")
		(25 "Edge.Cuts" user "Board Geometry/Outline")
		(27 "Margin" user)
		(31 "F.CrtYd" user "Package Geometry/Place Bound Top")
		(29 "B.CrtYd" user "Package Geometry/Place Bound Bottom")
		(35 "F.Fab" user "Ref Des/Assembly Top")
		(33 "B.Fab" user "Ref Des/Assembly Bottom")
	)
	(footprint ""
		(layer "F.Cu")
		(at 18.9484 -185.2422)
		(property "Reference" "C419"
			(at 0 0 0)
			(layer "F.SilkS")
			(hide yes)
			(effects
				(font
					(size 1.27 1.27)
				)
			)
		)
		(property "Value" "SCD015U25V2KX-GP"
			(at 1.1811 -2.7051 0)
			(unlocked yes)
			(layer "F.Fab")
			(hide yes)
			(effects
				(font
					(size 1.016 1.016)
					(thickness 0.1524)
				)
			)
		)
		(property "Device Type" "C402H22"
			(at 1.1811 -4.2291 0)
			(unlocked yes)
			(layer "F.Fab")
			(hide yes)
			(effects
				(font
					(size 1.016 1.016)
					(thickness 0.1524)
				)
			)
		)
		(duplicate_pad_numbers_are_jumpers no)
		(fp_rect
			(start -0.4318 0.9525)
			(end 0.4318 -0.9525)
			(stroke
				(width 0)
				(type default)
			)
			(fill no)
			(layer "F.CrtYd")
		)
		(fp_rect
			(start -0.4318 0.9525)
			(end 0.4318 -0.9525)
			(stroke
				(width 0)
				(type default)
			)
			(fill no)
			(layer "F.Fab")
		)
		(pad "1" smd custom
			(at 0 -0.4445)
			(size 0.1524 0.1524)
			(layers "F.Cu" "F.Mask" "F.Paste")
			(net "ADM1278_HS_P")
			(options
				(clearance outline)
				(anchor circle)
			)
			(primitives
				(gr_poly
					(pts
						(arc
							(start 0.3048 -0.2032)
							(mid 0.275042 -0.275042)
							(end 0.2032 -0.3048)
						)
						(arc
							(start -0.2032 -0.3048)
							(mid -0.275042 -0.275042)
							(end -0.3048 -0.2032)
						)
						(arc
							(start -0.3048 0.2032)
							(mid -0.275042 0.275042)
							(end -0.2032 0.3048)
						)
						(arc
							(start 0.2032 0.3048)
							(mid 0.275042 0.275042)
							(end 0.3048 0.2032)
						)
					)
					(width 0)
					(fill yes)
				)
			)
		)
		(pad "2" smd custom
			(at 0 0.4445)
			(size 0.1524 0.1524)
			(layers "F.Cu" "F.Mask" "F.Paste")
			(net "ADM1278_HS_N")
			(options
				(clearance outline)
				(anchor circle)
			)
			(primitives
				(gr_poly
					(pts
						(arc
							(start 0.3048 -0.2032)
							(mid 0.275042 -0.275042)
							(end 0.2032 -0.3048)
						)
						(arc
							(start -0.2032 -0.3048)
							(mid -0.275042 -0.275042)
							(end -0.3048 -0.2032)
						)
						(arc
							(start -0.3048 0.2032)
							(mid -0.275042 0.275042)
							(end -0.2032 0.3048)
						)
						(arc
							(start 0.2032 0.3048)
							(mid 0.275042 0.275042)
							(end 0.3048 0.2032)
						)
					)
					(width 0)
					(fill yes)
				)
			)
		)
	)
	(footprint ""
		(layer "F.Cu")
		(at 182.801006 -54.004972 90)
		(property "Reference" "L2"
			(at 0 0 90)
			(layer "F.SilkS")
			(hide yes)
			(effects
				(font
					(size 1.27 1.27)
				)
			)
		)
		(property "Value" "IND-10UH-103-GP"
			(at 0.3048 -12.065 90)
			(unlocked yes)
			(layer "F.Fab")
			(hide yes)
			(effects
				(font
					(size 1.016 1.016)
					(thickness 0.1524)
				)
			)
		)
		(property "Device Type" "L101100H158"
			(at 0.3048 -13.97 90)
			(unlocked yes)
			(layer "F.Fab")
			(hide yes)
			(effects
				(font
					(size 1.016 1.016)
					(thickness 0.1524)
				)
			)
		)
		(duplicate_pad_numbers_are_jumpers no)
		(fp_line
			(start 5.2578 -6.1849)
			(end -5.2578 -6.1849)
			(stroke
				(width 0.1524)
				(type default)
			)
			(layer "F.SilkS")
		)
		(fp_line
			(start -5.2578 -6.1849)
			(end -5.2578 6.1849)
			(stroke
				(width 0.1524)
				(type default)
			)
			(layer "F.SilkS")
		)
		(fp_line
			(start 5.2578 6.1849)
			(end 5.2578 -6.1849)
			(stroke
				(width 0.1524)
				(type default)
			)
			(layer "F.SilkS")
		)
		(fp_line
			(start -5.2578 6.1849)
			(end 5.2578 6.1849)
			(stroke
				(width 0.1524)
				(type default)
			)
			(layer "F.SilkS")
		)
		(fp_rect
			(start -5.5118 6.2738)
			(end 5.5118 -6.2738)
			(stroke
				(width 0)
				(type default)
			)
			(fill no)
			(layer "F.CrtYd")
		)
		(fp_poly
			(pts
				(xy -5.5118 -6.2738) (xy 5.5118 -6.2738) (xy 5.5118 6.2738) (xy -5.5118 6.2738)
			)
			(stroke
				(width 0)
				(type default)
			)
			(fill no)
			(layer "F.Fab")
		)
		(pad "1" smd rect
			(at 0 -4.7625 90)
			(size 3.2512 2.3368)
			(layers "F.Cu" "F.Mask" "F.Paste")
			(net "DUT_AVD_PCIE")
		)
		(pad "2" smd rect
			(at 0 4.7625 90)
			(size 3.2512 2.3368)
			(layers "F.Cu" "F.Mask" "F.Paste")
			(net "DUT_AVD_PCIE_Q")
		)
	)
	(footprint ""
		(layer "F.Cu")
		(at 317.408052 -212.420454 180)
		(property "Reference" "C69"
			(at 0 0 180)
			(layer "F.SilkS")
			(hide yes)
			(effects
				(font
					(size 1.27 1.27)
				)
			)
		)
		(property "Value" "SCD22U10V2KX-1GP"
			(at 1.1811 -2.7051 180)
			(unlocked yes)
			(layer "F.Fab")
			(hide yes)
			(effects
				(font
					(size 1.016 1.016)
					(thickness 0.1524)
				)
			)
		)
		(property "Device Type" "C402H22"
			(at 1.1811 -4.2291 180)
			(unlocked yes)
			(layer "F.Fab")
			(hide yes)
			(effects
				(font
					(size 1.016 1.016)
					(thickness 0.1524)
				)
			)
		)
		(duplicate_pad_numbers_are_jumpers no)
		(fp_rect
			(start -0.4318 0.9525)
			(end 0.4318 -0.9525)
			(stroke
				(width 0)
				(type default)
			)
			(fill no)
			(layer "F.CrtYd")
		)
		(fp_rect
			(start -0.4318 0.9525)
			(end 0.4318 -0.9525)
			(stroke
				(width 0)
				(type default)
			)
			(fill no)
			(layer "F.Fab")
		)
		(pad "1" smd custom
			(at 0 -0.4445 180)
			(size 0.1524 0.1524)
			(layers "F.Cu" "F.Mask" "F.Paste")
			(net "PCIE_TX_CAP_N23")
			(options
				(clearance outline)
				(anchor circle)
			)
			(primitives
				(gr_poly
					(pts
						(arc
							(start 0.3048 -0.2032)
							(mid 0.275042 -0.275042)
							(end 0.2032 -0.3048)
						)
						(arc
							(start -0.2032 -0.3048)
							(mid -0.275042 -0.275042)
							(end -0.3048 -0.2032)
						)
						(arc
							(start -0.3048 0.2032)
							(mid -0.275042 0.275042)
							(end -0.2032 0.3048)
						)
						(arc
							(start 0.2032 0.3048)
							(mid 0.275042 0.275042)
							(end 0.3048 0.2032)
						)
					)
					(width 0)
					(fill yes)
				)
			)
		)
		(pad "2" smd custom
			(at 0 0.4445 180)
			(size 0.1524 0.1524)
			(layers "F.Cu" "F.Mask" "F.Paste")
			(net "PCIE_TX_N23")
			(options
				(clearance outline)
				(anchor circle)
			)
			(primitives
				(gr_poly
					(pts
						(arc
							(start 0.3048 -0.2032)
							(mid 0.275042 -0.275042)
							(end 0.2032 -0.3048)
						)
						(arc
							(start -0.2032 -0.3048)
							(mid -0.275042 -0.275042)
							(end -0.3048 -0.2032)
						)
						(arc
							(start -0.3048 0.2032)
							(mid -0.275042 0.275042)
							(end -0.2032 0.3048)
						)
						(arc
							(start 0.2032 0.3048)
							(mid 0.275042 0.275042)
							(end 0.3048 0.2032)
						)
					)
					(width 0)
					(fill yes)
				)
			)
		)
	)
	(footprint ""
		(layer "F.Cu")
		(at 54.229 -130.048)
		(property "Reference" "C189"
			(at 0 0 0)
			(layer "F.SilkS")
			(hide yes)
			(effects
				(font
					(size 1.27 1.27)
				)
			)
		)
		(property "Value" "SCD1U16V2KX-3GP"
			(at 1.1811 -2.7051 0)
			(unlocked yes)
			(layer "F.Fab")
			(hide yes)
			(effects
				(font
					(size 1.016 1.016)
					(thickness 0.1524)
				)
			)
		)
		(property "Device Type" "C402H22"
			(at 1.1811 -4.2291 0)
			(unlocked yes)
			(layer "F.Fab")
			(hide yes)
			(effects
				(font
					(size 1.016 1.016)
					(thickness 0.1524)
				)
			)
		)
		(duplicate_pad_numbers_are_jumpers no)
		(fp_rect
			(start -0.4318 0.9525)
			(end 0.4318 -0.9525)
			(stroke
				(width 0)
				(type default)
			)
			(fill no)
			(layer "F.CrtYd")
		)
		(fp_rect
			(start -0.4318 0.9525)
			(end 0.4318 -0.9525)
			(stroke
				(width 0)
				(type default)
			)
			(fill no)
			(layer "F.Fab")
		)
		(pad "1" smd custom
			(at 0 -0.4445)
			(size 0.1524 0.1524)
			(layers "F.Cu" "F.Mask" "F.Paste")
			(net "ADCAV33")
			(options
				(clearance outline)
				(anchor circle)
			)
			(primitives
				(gr_poly
					(pts
						(arc
							(start 0.3048 -0.2032)
							(mid 0.275042 -0.275042)
							(end 0.2032 -0.3048)
						)
						(arc
							(start -0.2032 -0.3048)
							(mid -0.275042 -0.275042)
							(end -0.3048 -0.2032)
						)
						(arc
							(start -0.3048 0.2032)
							(mid -0.275042 0.275042)
							(end -0.2032 0.3048)
						)
						(arc
							(start 0.2032 0.3048)
							(mid 0.275042 0.275042)
							(end 0.3048 0.2032)
						)
					)
					(width 0)
					(fill yes)
				)
			)
		)
		(pad "2" smd custom
			(at 0 0.4445)
			(size 0.1524 0.1524)
			(layers "F.Cu" "F.Mask" "F.Paste")
			(net "ADCVREFFP")
			(options
				(clearance outline)
				(anchor circle)
			)
			(primitives
				(gr_poly
					(pts
						(arc
							(start 0.3048 -0.2032)
							(mid 0.275042 -0.275042)
							(end 0.2032 -0.3048)
						)
						(arc
							(start -0.2032 -0.3048)
							(mid -0.275042 -0.275042)
							(end -0.3048 -0.2032)
						)
						(arc
							(start -0.3048 0.2032)
							(mid -0.275042 0.275042)
							(end -0.2032 0.3048)
						)
						(arc
							(start 0.2032 0.3048)
							(mid 0.275042 0.275042)
							(end 0.3048 0.2032)
						)
					)
					(width 0)
					(fill yes)
				)
			)
		)
	)
	(footprint ""
		(layer "F.Cu")
		(at 27.305 -116.713)
		(property "Reference" "R233"
			(at 0 0 0)
			(layer "F.SilkS")
			(hide yes)
			(effects
				(font
					(size 1.27 1.27)
				)
			)
		)
		(property "Value" "100KR2F-L1-GP"
			(at 0.064008 -3.993896 0)
			(unlocked yes)
			(layer "F.Fab")
			(hide yes)
			(effects
				(font
					(size 1.016 1.016)
					(thickness 0.1524)
				)
			)
		)
		(property "Device Type" "R402H16"
			(at 0.064008 -5.517896 0)
			(unlocked yes)
			(layer "F.Fab")
			(hide yes)
			(effects
				(font
					(size 1.016 1.016)
					(thickness 0.1524)
				)
			)
		)
		(duplicate_pad_numbers_are_jumpers no)
		(fp_line
			(start -0.508 -0.9398)
			(end -0.508 0.9398)
			(stroke
				(width 0.1524)
				(type default)
			)
			(layer "F.SilkS")
		)
		(fp_line
			(start 0.508 -0.9398)
			(end -0.508 -0.9398)
			(stroke
				(width 0.1524)
				(type default)
			)
			(layer "F.SilkS")
		)
		(fp_rect
			(start -0.508 0.9398)
			(end 0.508 -0.9398)
			(stroke
				(width 0)
				(type default)
			)
			(fill no)
			(layer "F.CrtYd")
		)
		(fp_rect
			(start -0.508 0.9398)
			(end 0.508 -0.9398)
			(stroke
				(width 0)
				(type default)
			)
			(fill no)
			(layer "F.Fab")
		)
		(pad "1" smd custom
			(at 0 -0.4445)
			(size 0.1397 0.1397)
			(layers "F.Cu" "F.Mask" "F.Paste")
			(net "TP_LPC_CPU_CLKOUT0")
			(options
				(clearance outline)
				(anchor circle)
			)
			(primitives
				(gr_poly
					(pts
						(arc
							(start -0.1778 -0.2794)
							(mid -0.249642 -0.249642)
							(end -0.2794 -0.1778)
						)
						(arc
							(start -0.2794 0.1778)
							(mid -0.249642 0.249642)
							(end -0.1778 0.2794)
						)
						(arc
							(start 0.1778 0.2794)
							(mid 0.249642 0.249642)
							(end 0.2794 0.1778)
						)
						(arc
							(start 0.2794 -0.1778)
							(mid 0.249642 -0.249642)
							(end 0.1778 -0.2794)
						)
					)
					(width 0)
					(fill yes)
				)
			)
		)
		(pad "2" smd custom
			(at 0 0.4445)
			(size 0.1397 0.1397)
			(layers "F.Cu" "F.Mask" "F.Paste")
			(net "GND")
			(options
				(clearance outline)
				(anchor circle)
			)
			(primitives
				(gr_poly
					(pts
						(arc
							(start -0.1778 -0.2794)
							(mid -0.249642 -0.249642)
							(end -0.2794 -0.1778)
						)
						(arc
							(start -0.2794 0.1778)
							(mid -0.249642 0.249642)
							(end -0.1778 0.2794)
						)
						(arc
							(start 0.1778 0.2794)
							(mid 0.249642 0.249642)
							(end 0.2794 0.1778)
						)
						(arc
							(start 0.2794 -0.1778)
							(mid 0.249642 -0.249642)
							(end 0.1778 -0.2794)
						)
					)
					(width 0)
					(fill yes)
				)
			)
		)
	)
	(footprint ""
		(layer "F.Cu")
		(at 6.8072 -182.9816 90)
		(property "Reference" "R688"
			(at 0 0 90)
			(layer "F.SilkS")
			(hide yes)
			(effects
				(font
					(size 1.27 1.27)
				)
			)
		)
		(property "Value" "10KR2J-3-GP"
			(at 0.064008 -3.993896 90)
			(unlocked yes)
			(layer "F.Fab")
			(hide yes)
			(effects
				(font
					(size 1.016 1.016)
					(thickness 0.1524)
				)
			)
		)
		(property "Device Type" "R402H16"
			(at 0.064008 -5.517896 90)
			(unlocked yes)
			(layer "F.Fab")
			(hide yes)
			(effects
				(font
					(size 1.016 1.016)
					(thickness 0.1524)
				)
			)
		)
		(duplicate_pad_numbers_are_jumpers no)
		(fp_line
			(start 0.508 -0.9398)
			(end -0.508 -0.9398)
			(stroke
				(width 0.1524)
				(type default)
			)
			(layer "F.SilkS")
		)
		(fp_line
			(start -0.508 -0.9398)
			(end -0.508 0.9398)
			(stroke
				(width 0.1524)
				(type default)
			)
			(layer "F.SilkS")
		)
		(fp_rect
			(start -0.508 0.9398)
			(end 0.508 -0.9398)
			(stroke
				(width 0)
				(type default)
			)
			(fill no)
			(layer "F.CrtYd")
		)
		(fp_rect
			(start -0.508 0.9398)
			(end 0.508 -0.9398)
			(stroke
				(width 0)
				(type default)
			)
			(fill no)
			(layer "F.Fab")
		)
		(pad "1" smd custom
			(at 0 -0.4445 90)
			(size 0.1397 0.1397)
			(layers "F.Cu" "F.Mask" "F.Paste")
			(net "GND")
			(options
				(clearance outline)
				(anchor circle)
			)
			(primitives
				(gr_poly
					(pts
						(arc
							(start -0.1778 -0.2794)
							(mid -0.249642 -0.249642)
							(end -0.2794 -0.1778)
						)
						(arc
							(start -0.2794 0.1778)
							(mid -0.249642 0.249642)
							(end -0.1778 0.2794)
						)
						(arc
							(start 0.1778 0.2794)
							(mid 0.249642 0.249642)
							(end 0.2794 0.1778)
						)
						(arc
							(start 0.2794 -0.1778)
							(mid 0.249642 -0.249642)
							(end 0.1778 -0.2794)
						)
					)
					(width 0)
					(fill yes)
				)
			)
		)
		(pad "2" smd custom
			(at 0 0.4445 90)
			(size 0.1397 0.1397)
			(layers "F.Cu" "F.Mask" "F.Paste")
			(net "MB0_RETRY_R")
			(options
				(clearance outline)
				(anchor circle)
			)
			(primitives
				(gr_poly
					(pts
						(arc
							(start -0.1778 -0.2794)
							(mid -0.249642 -0.249642)
							(end -0.2794 -0.1778)
						)
						(arc
							(start -0.2794 0.1778)
							(mid -0.249642 0.249642)
							(end -0.1778 0.2794)
						)
						(arc
							(start 0.1778 0.2794)
							(mid 0.249642 0.249642)
							(end 0.2794 0.1778)
						)
						(arc
							(start 0.2794 -0.1778)
							(mid 0.249642 -0.249642)
							(end 0.1778 -0.2794)
						)
					)
					(width 0)
					(fill yes)
				)
			)
		)
	)
	(footprint ""
		(layer "F.Cu")
		(at 49.911 -184.15 -90)
		(property "Reference" "C708"
			(at 0 0 270)
			(layer "F.SilkS")
			(hide yes)
			(effects
				(font
					(size 1.27 1.27)
				)
			)
		)
		(property "Value" "SC220P50V3JN-GP"
			(at 0 -2.8194 270)
			(unlocked yes)
			(layer "F.Fab")
			(hide yes)
			(effects
				(font
					(size 1.016 1.016)
					(thickness 0.1524)
				)
			)
		)
		(property "Device Type" "C603H36"
			(at 0 -4.3434 270)
			(unlocked yes)
			(layer "F.Fab")
			(hide yes)
			(effects
				(font
					(size 1.016 1.016)
					(thickness 0.1524)
				)
			)
		)
		(duplicate_pad_numbers_are_jumpers no)
		(fp_line
			(start 0.508 0)
			(end -0.508 0)
			(stroke
				(width 0.2032)
				(type default)
			)
			(layer "F.SilkS")
		)
		(fp_rect
			(start -0.5842 1.3335)
			(end 0.5842 -1.3335)
			(stroke
				(width 0)
				(type default)
			)
			(fill no)
			(layer "F.CrtYd")
		)
		(fp_rect
			(start -0.5842 1.3335)
			(end 0.5842 -1.3335)
			(stroke
				(width 0)
				(type default)
			)
			(fill no)
			(layer "F.Fab")
		)
		(pad "1" smd custom
			(at 0 -0.762 270)
			(size 0.2159 0.2159)
			(layers "F.Cu" "F.Mask" "F.Paste")
			(net "BUF_I2C8_CLKBUF1_SDA_R")
			(options
				(clearance outline)
				(anchor circle)
			)
			(primitives
				(gr_poly
					(pts
						(arc
							(start -0.3302 -0.4318)
							(mid -0.402042 -0.402042)
							(end -0.4318 -0.3302)
						)
						(arc
							(start -0.4318 0.3302)
							(mid -0.402042 0.402042)
							(end -0.3302 0.4318)
						)
						(arc
							(start 0.3302 0.4318)
							(mid 0.402042 0.402042)
							(end 0.4318 0.3302)
						)
						(arc
							(start 0.4318 -0.3302)
							(mid 0.402042 -0.402042)
							(end 0.3302 -0.4318)
						)
					)
					(width 0)
					(fill yes)
				)
			)
		)
		(pad "2" smd custom
			(at 0 0.762 270)
			(size 0.2159 0.2159)
			(layers "F.Cu" "F.Mask" "F.Paste")
			(net "GND")
			(options
				(clearance outline)
				(anchor circle)
			)
			(primitives
				(gr_poly
					(pts
						(arc
							(start -0.3302 -0.4318)
							(mid -0.402042 -0.402042)
							(end -0.4318 -0.3302)
						)
						(arc
							(start -0.4318 0.3302)
							(mid -0.402042 0.402042)
							(end -0.3302 0.4318)
						)
						(arc
							(start 0.3302 0.4318)
							(mid 0.402042 0.402042)
							(end 0.4318 0.3302)
						)
						(arc
							(start 0.4318 -0.3302)
							(mid 0.402042 -0.402042)
							(end 0.3302 -0.4318)
						)
					)
					(width 0)
					(fill yes)
				)
			)
		)
	)
	(footprint ""
		(layer "F.Cu")
		(at 79.883 -183.261)
		(property "Reference" "R9034"
			(at 0 0 0)
			(layer "F.SilkS")
			(hide yes)
			(effects
				(font
					(size 1.27 1.27)
				)
			)
		)
		(property "Value" "4K7R2F-GP"
			(at 0.064008 -3.993896 0)
			(unlocked yes)
			(layer "F.Fab")
			(hide yes)
			(effects
				(font
					(size 1.016 1.016)
					(thickness 0.1524)
				)
			)
		)
		(property "Device Type" "R402H16"
			(at 0.064008 -5.517896 0)
			(unlocked yes)
			(layer "F.Fab")
			(hide yes)
			(effects
				(font
					(size 1.016 1.016)
					(thickness 0.1524)
				)
			)
		)
		(duplicate_pad_numbers_are_jumpers no)
		(fp_line
			(start -0.508 -0.9398)
			(end -0.508 0.9398)
			(stroke
				(width 0.1524)
				(type default)
			)
			(layer "F.SilkS")
		)
		(fp_line
			(start 0.508 -0.9398)
			(end -0.508 -0.9398)
			(stroke
				(width 0.1524)
				(type default)
			)
			(layer "F.SilkS")
		)
		(fp_rect
			(start -0.508 0.9398)
			(end 0.508 -0.9398)
			(stroke
				(width 0)
				(type default)
			)
			(fill no)
			(layer "F.CrtYd")
		)
		(fp_rect
			(start -0.508 0.9398)
			(end 0.508 -0.9398)
			(stroke
				(width 0)
				(type default)
			)
			(fill no)
			(layer "F.Fab")
		)
		(pad "1" smd custom
			(at 0 -0.4445)
			(size 0.1397 0.1397)
			(layers "F.Cu" "F.Mask" "F.Paste")
			(net "SSD_PERST#5")
			(options
				(clearance outline)
				(anchor circle)
			)
			(primitives
				(gr_poly
					(pts
						(arc
							(start -0.1778 -0.2794)
							(mid -0.249642 -0.249642)
							(end -0.2794 -0.1778)
						)
						(arc
							(start -0.2794 0.1778)
							(mid -0.249642 0.249642)
							(end -0.1778 0.2794)
						)
						(arc
							(start 0.1778 0.2794)
							(mid 0.249642 0.249642)
							(end 0.2794 0.1778)
						)
						(arc
							(start 0.2794 -0.1778)
							(mid 0.249642 -0.249642)
							(end 0.1778 -0.2794)
						)
					)
					(width 0)
					(fill yes)
				)
			)
		)
		(pad "2" smd custom
			(at 0 0.4445)
			(size 0.1397 0.1397)
			(layers "F.Cu" "F.Mask" "F.Paste")
			(net "GND")
			(options
				(clearance outline)
				(anchor circle)
			)
			(primitives
				(gr_poly
					(pts
						(arc
							(start -0.1778 -0.2794)
							(mid -0.249642 -0.249642)
							(end -0.2794 -0.1778)
						)
						(arc
							(start -0.2794 0.1778)
							(mid -0.249642 0.249642)
							(end -0.1778 0.2794)
						)
						(arc
							(start 0.1778 0.2794)
							(mid 0.249642 0.249642)
							(end 0.2794 0.1778)
						)
						(arc
							(start 0.2794 -0.1778)
							(mid 0.249642 -0.249642)
							(end 0.1778 -0.2794)
						)
					)
					(width 0)
					(fill yes)
				)
			)
		)
	)
)
